(kicad_pcb
	(version 20260206)
	(generator "pcbnew")
	(generator_version "10.0")
	(general
		(thickness 1.6)
		(legacy_teardrops no)
	)
	(paper "A4")
	(title_block
		(title "panther-plus-userver — 13130-1b_20150205.brd")
		(comment 1 "Honey Badger (Wiwynn) / footprints 512-519 of 1509")
	)
	(layers
		(0 "F.Cu" signal "TOP")
		(4 "In1.Cu" signal "L2")
		(6 "In2.Cu" signal "L3")
		(8 "In3.Cu" signal "L4")
		(10 "In4.Cu" signal "L5")
		(12 "In5.Cu" signal "L6")
		(14 "In6.Cu" signal "L7")
		(16 "In7.Cu" signal "L8")
		(18 "In8.Cu" signal "L9")
		(20 "In9.Cu" signal "L10")
		(22 "In10.Cu" signal "L11")
		(2 "B.Cu" signal "BOTTOM")
		(9 "F.Adhes" user "F.Adhesive")
		(11 "B.Adhes" user "B.Adhesive")
		(13 "F.Paste" user "Package Geometry/Pastemask Top")
		(15 "B.Paste" user "Package Geometry/Pastemask Bottom")
		(5 "F.SilkS" user "Ref Des/Silkscreen Top")
		(7 "B.SilkS" user "Ref Des/Silkscreen Bottom")
		(1 "F.Mask" user "Board Geometry/Soldermask Top")
		(3 "B.Mask" user "Board Geometry/Soldermask Bottom")
		(17 "Dwgs.User" user "User.Drawings")
		(19 "Cmts.User" user "User.Comments")
		(21 "Eco1.User" user "User.Eco1")
		(23 "Eco2.User" user "User.Eco2")
		(25 "Edge.Cuts" user "Board Geometry/Outline")
		(27 "Margin" user)
		(31 "F.CrtYd" user "Package Geometry/Place Bound Top")
		(29 "B.CrtYd" user "Package Geometry/Place Bound Bottom")
		(35 "F.Fab" user "Ref Des/Assembly Top")
		(33 "B.Fab" user "Ref Des/Assembly Bottom")
	)
	(footprint ""
		(layer "F.Cu")
		(at 52.767992 -28.796234 90)
		(property "Reference" "U18"
			(at 0 0 90)
			(layer "F.SilkS")
			(hide yes)
			(effects
				(font
					(size 1.27 1.27)
				)
			)
		)
		(property "Value" "W25Q64FVSSIG-GP"
			(at 0 -13.1572 90)
			(unlocked yes)
			(layer "F.Fab")
			(hide yes)
			(effects
				(font
					(size 1.016 1.016)
					(thickness 0.1524)
				)
			)
		)
		(property "Device Type" "SOIC8-1H86"
			(at 0 -14.6812 90)
			(unlocked yes)
			(layer "F.Fab")
			(hide yes)
			(effects
				(font
					(size 1.016 1.016)
					(thickness 0.1524)
				)
			)
		)
		(duplicate_pad_numbers_are_jumpers no)
		(fp_line
			(start 2.1336 -2.4003)
			(end -2.8194 -2.4003)
			(stroke
				(width 0.1524)
				(type default)
			)
			(layer "F.SilkS")
		)
		(fp_line
			(start -2.8194 -2.4003)
			(end -2.8194 2.4003)
			(stroke
				(width 0.1524)
				(type default)
			)
			(layer "F.SilkS")
		)
		(fp_line
			(start 2.1336 -2.3876)
			(end 2.1336 -2.4003)
			(stroke
				(width 0.1524)
				(type default)
			)
			(layer "F.SilkS")
		)
		(fp_line
			(start -2.8194 -0.508)
			(end -2.8194 2.4003)
			(stroke
				(width 0.1524)
				(type default)
			)
			(layer "F.SilkS")
		)
		(fp_line
			(start -2.3114 0)
			(end -2.8194 -0.508)
			(stroke
				(width 0.1524)
				(type default)
			)
			(layer "F.SilkS")
		)
		(fp_line
			(start -2.8194 0.508)
			(end -2.3114 0)
			(stroke
				(width 0.1524)
				(type default)
			)
			(layer "F.SilkS")
		)
		(fp_line
			(start -2.6416 2.3114)
			(end -2.6416 4.0767)
			(stroke
				(width 0.508)
				(type default)
			)
			(layer "F.SilkS")
		)
		(fp_line
			(start 2.1336 2.4003)
			(end 2.1336 -2.4003)
			(stroke
				(width 0.1524)
				(type default)
			)
			(layer "F.SilkS")
		)
		(fp_line
			(start -2.8194 2.4003)
			(end 2.1336 2.4003)
			(stroke
				(width 0.1524)
				(type default)
			)
			(layer "F.SilkS")
		)
		(fp_poly
			(pts
				(xy -2.2352 2.4003) (xy 2.1336 2.4003) (xy 2.1336 -2.4003) (xy -2.2352 -2.4003)
			)
			(stroke
				(width 0)
				(type default)
			)
			(fill yes)
			(layer "F.SilkS")
		)
		(fp_rect
			(start -2.8956 4.3307)
			(end 2.8956 -4.3307)
			(stroke
				(width 0)
				(type default)
			)
			(fill no)
			(layer "F.CrtYd")
		)
		(fp_rect
			(start -2.8956 4.3307)
			(end 2.8956 -4.3307)
			(stroke
				(width 0)
				(type default)
			)
			(fill no)
			(layer "F.Fab")
		)
		(pad "1" smd rect
			(at -1.905 3.441954 90)
			(size 0.635 1.524)
			(layers "F.Cu" "F.Mask" "F.Paste")
			(net "SPI_CS0_N_M_1")
		)
		(pad "2" smd rect
			(at -0.635 3.441954 90)
			(size 0.635 1.524)
			(layers "F.Cu" "F.Mask" "F.Paste")
			(net "SPI_MISO_R_1")
		)
		(pad "3" smd rect
			(at 0.635 3.441954 90)
			(size 0.635 1.524)
			(layers "F.Cu" "F.Mask" "F.Paste")
			(net "SPI_WP_R_N_1")
		)
		(pad "4" smd rect
			(at 1.905 3.441954 90)
			(size 0.635 1.524)
			(layers "F.Cu" "F.Mask" "F.Paste")
			(net "GND")
		)
		(pad "5" smd rect
			(at 1.905 -3.441954 90)
			(size 0.635 1.524)
			(layers "F.Cu" "F.Mask" "F.Paste")
			(net "SPI_MOSI_R_1")
		)
		(pad "6" smd rect
			(at 0.635 -3.441954 90)
			(size 0.635 1.524)
			(layers "F.Cu" "F.Mask" "F.Paste")
			(net "SPI_SCLK_R_1")
		)
		(pad "7" smd rect
			(at -0.635 -3.441954 90)
			(size 0.635 1.524)
			(layers "F.Cu" "F.Mask" "F.Paste")
			(net "SPI_HOLD#")
		)
		(pad "8" smd rect
			(at -1.905 -3.441954 90)
			(size 0.635 1.524)
			(layers "F.Cu" "F.Mask" "F.Paste")
			(net "P3V3_CPU")
		)
	)
	(footprint ""
		(layer "F.Cu")
		(at 197.2818 -33.782 90)
		(property "Reference" "PR109"
			(at 0 0 90)
			(layer "F.SilkS")
			(hide yes)
			(effects
				(font
					(size 1.27 1.27)
				)
			)
		)
		(property "Value" "0R3J-0-U-GP"
			(at -0.0254 -2.0193 90)
			(unlocked yes)
			(layer "F.Fab")
			(hide yes)
			(effects
				(font
					(size 1.016 1.016)
					(thickness 0.1524)
				)
			)
		)
		(property "Device Type" "R603H22"
			(at -0.0254 -3.5433 90)
			(unlocked yes)
			(layer "F.Fab")
			(hide yes)
			(effects
				(font
					(size 1.016 1.016)
					(thickness 0.1524)
				)
			)
		)
		(duplicate_pad_numbers_are_jumpers no)
		(fp_line
			(start 0.4318 0)
			(end 0.2032 0)
			(stroke
				(width 0.2032)
				(type default)
			)
			(layer "F.SilkS")
		)
		(fp_line
			(start -0.2032 0)
			(end -0.4191 0)
			(stroke
				(width 0.2032)
				(type default)
			)
			(layer "F.SilkS")
		)
		(fp_rect
			(start -0.635 1.1811)
			(end 0.635 -1.1811)
			(stroke
				(width 0)
				(type default)
			)
			(fill no)
			(layer "F.CrtYd")
		)
		(fp_rect
			(start -0.635 1.1811)
			(end 0.635 -1.1811)
			(stroke
				(width 0)
				(type default)
			)
			(fill no)
			(layer "F.Fab")
		)
		(pad "1" smd custom
			(at 0 -0.6604 90)
			(size 0.19685 0.19685)
			(layers "F.Cu" "F.Mask" "F.Paste")
			(net "VR_PVDDR_A_GH1")
			(options
				(clearance outline)
				(anchor circle)
			)
			(primitives
				(gr_poly
					(pts
						(arc
							(start 0.508 -0.2921)
							(mid 0.478242 -0.363942)
							(end 0.4064 -0.3937)
						)
						(arc
							(start -0.4064 -0.3937)
							(mid -0.478242 -0.363942)
							(end -0.508 -0.2921)
						)
						(arc
							(start -0.508 0.2921)
							(mid -0.478242 0.363942)
							(end -0.4064 0.3937)
						)
						(arc
							(start 0.4064 0.3937)
							(mid 0.478242 0.363942)
							(end 0.508 0.2921)
						)
					)
					(width 0)
					(fill yes)
				)
			)
		)
		(pad "2" smd custom
			(at 0 0.6604 90)
			(size 0.19685 0.19685)
			(layers "F.Cu" "F.Mask" "F.Paste")
			(net "VR_PVDDR_A_GH1_R")
			(options
				(clearance outline)
				(anchor circle)
			)
			(primitives
				(gr_poly
					(pts
						(arc
							(start 0.508 -0.2921)
							(mid 0.478242 -0.363942)
							(end 0.4064 -0.3937)
						)
						(arc
							(start -0.4064 -0.3937)
							(mid -0.478242 -0.363942)
							(end -0.508 -0.2921)
						)
						(arc
							(start -0.508 0.2921)
							(mid -0.478242 0.363942)
							(end -0.4064 0.3937)
						)
						(arc
							(start 0.4064 0.3937)
							(mid 0.478242 0.363942)
							(end 0.508 0.2921)
						)
					)
					(width 0)
					(fill yes)
				)
			)
		)
	)
	(footprint ""
		(layer "F.Cu")
		(at 46.2788 -34.417 180)
		(property "Reference" "C339"
			(at 0 0 180)
			(layer "F.SilkS")
			(hide yes)
			(effects
				(font
					(size 1.27 1.27)
				)
			)
		)
		(property "Value" "SCD1U10V2KX-5GP"
			(at 1.8923 -1.2065 180)
			(unlocked yes)
			(layer "F.Fab")
			(hide yes)
			(effects
				(font
					(size 1.016 1.016)
					(thickness 0.1524)
				)
			)
		)
		(property "Device Type" "C402H22"
			(at 1.8923 -2.7305 180)
			(unlocked yes)
			(layer "F.Fab")
			(hide yes)
			(effects
				(font
					(size 1.016 1.016)
					(thickness 0.1524)
				)
			)
		)
		(duplicate_pad_numbers_are_jumpers no)
		(fp_rect
			(start -0.381 0.7366)
			(end 0.381 -0.7366)
			(stroke
				(width 0)
				(type default)
			)
			(fill no)
			(layer "F.CrtYd")
		)
		(fp_rect
			(start -0.381 0.7366)
			(end 0.381 -0.7366)
			(stroke
				(width 0)
				(type default)
			)
			(fill no)
			(layer "F.Fab")
		)
		(pad "1" smd custom
			(at 0 -0.4572 180)
			(size 0.1143 0.1143)
			(layers "F.Cu" "F.Mask" "F.Paste")
			(net "P3V3_CPU")
			(options
				(clearance outline)
				(anchor circle)
			)
			(primitives
				(gr_poly
					(pts
						(arc
							(start -0.254 -0.1778)
							(mid -0.239121 -0.213721)
							(end -0.2032 -0.2286)
						)
						(arc
							(start 0.2032 -0.2286)
							(mid 0.239121 -0.213721)
							(end 0.254 -0.1778)
						)
						(arc
							(start 0.254 0.1778)
							(mid 0.239121 0.213721)
							(end 0.2032 0.2286)
						)
						(arc
							(start -0.2032 0.2286)
							(mid -0.239121 0.213721)
							(end -0.254 0.1778)
						)
					)
					(width 0)
					(fill yes)
				)
			)
		)
		(pad "2" smd custom
			(at 0 0.4572 180)
			(size 0.1143 0.1143)
			(layers "F.Cu" "F.Mask" "F.Paste")
			(net "GND")
			(options
				(clearance outline)
				(anchor circle)
			)
			(primitives
				(gr_poly
					(pts
						(arc
							(start -0.254 -0.1778)
							(mid -0.239121 -0.213721)
							(end -0.2032 -0.2286)
						)
						(arc
							(start 0.2032 -0.2286)
							(mid 0.239121 -0.213721)
							(end 0.254 -0.1778)
						)
						(arc
							(start 0.254 0.1778)
							(mid 0.239121 0.213721)
							(end 0.2032 0.2286)
						)
						(arc
							(start -0.2032 0.2286)
							(mid -0.239121 0.213721)
							(end -0.254 0.1778)
						)
					)
					(width 0)
					(fill yes)
				)
			)
		)
	)
	(footprint ""
		(layer "F.Cu")
		(at 74.0664 -47.9552 90)
		(property "Reference" "R66"
			(at 0 0 90)
			(layer "F.SilkS")
			(hide yes)
			(effects
				(font
					(size 1.27 1.27)
				)
			)
		)
		(property "Value" "4K7R2F-GP"
			(at 0.064008 -3.993896 90)
			(unlocked yes)
			(layer "F.Fab")
			(hide yes)
			(effects
				(font
					(size 1.016 1.016)
					(thickness 0.1524)
				)
			)
		)
		(property "Device Type" "R402H16"
			(at 0.064008 -5.517896 90)
			(unlocked yes)
			(layer "F.Fab")
			(hide yes)
			(effects
				(font
					(size 1.016 1.016)
					(thickness 0.1524)
				)
			)
		)
		(duplicate_pad_numbers_are_jumpers no)
		(fp_rect
			(start -0.381 0.8382)
			(end 0.381 -0.8382)
			(stroke
				(width 0)
				(type default)
			)
			(fill no)
			(layer "F.CrtYd")
		)
		(fp_rect
			(start -0.381 0.8382)
			(end 0.381 -0.8382)
			(stroke
				(width 0)
				(type default)
			)
			(fill no)
			(layer "F.Fab")
		)
		(pad "1" smd custom
			(at 0 -0.4318 90)
			(size 0.127 0.127)
			(layers "F.Cu" "F.Mask" "F.Paste")
			(net "P3V3")
			(options
				(clearance outline)
				(anchor circle)
			)
			(primitives
				(gr_poly
					(pts
						(arc
							(start -0.2032 -0.2794)
							(mid -0.239121 -0.264521)
							(end -0.254 -0.2286)
						)
						(arc
							(start -0.254 0.2286)
							(mid -0.239121 0.264521)
							(end -0.2032 0.2794)
						)
						(arc
							(start 0.2032 0.2794)
							(mid 0.239121 0.264521)
							(end 0.254 0.2286)
						)
						(arc
							(start 0.254 -0.2286)
							(mid 0.239121 -0.264521)
							(end 0.2032 -0.2794)
						)
					)
					(width 0)
					(fill yes)
				)
			)
		)
		(pad "2" smd custom
			(at 0 0.4318 90)
			(size 0.127 0.127)
			(layers "F.Cu" "F.Mask" "F.Paste")
			(net "SMB_CLK1_SPKR")
			(options
				(clearance outline)
				(anchor circle)
			)
			(primitives
				(gr_poly
					(pts
						(arc
							(start -0.2032 -0.2794)
							(mid -0.239121 -0.264521)
							(end -0.254 -0.2286)
						)
						(arc
							(start -0.254 0.2286)
							(mid -0.239121 0.264521)
							(end -0.2032 0.2794)
						)
						(arc
							(start 0.2032 0.2794)
							(mid 0.239121 0.264521)
							(end 0.254 0.2286)
						)
						(arc
							(start 0.254 -0.2286)
							(mid 0.239121 -0.264521)
							(end 0.2032 -0.2794)
						)
					)
					(width 0)
					(fill yes)
				)
			)
		)
	)
	(footprint ""
		(layer "F.Cu")
		(at 186.0042 -26.5938 180)
		(property "Reference" "PC109"
			(at 0 0 180)
			(layer "F.SilkS")
			(hide yes)
			(effects
				(font
					(size 1.27 1.27)
				)
			)
		)
		(property "Value" "SCD22U16V3KX-2-GP"
			(at -0.0254 -2.0193 180)
			(unlocked yes)
			(layer "F.Fab")
			(hide yes)
			(effects
				(font
					(size 1.016 1.016)
					(thickness 0.1524)
				)
			)
		)
		(property "Device Type" "C603H36"
			(at -0.0254 -3.5433 180)
			(unlocked yes)
			(layer "F.Fab")
			(hide yes)
			(effects
				(font
					(size 1.016 1.016)
					(thickness 0.1524)
				)
			)
		)
		(duplicate_pad_numbers_are_jumpers no)
		(fp_line
			(start -0.4064 0)
			(end 0.4064 0)
			(stroke
				(width 0.2286)
				(type default)
			)
			(layer "F.SilkS")
		)
		(fp_rect
			(start -0.635 1.1811)
			(end 0.635 -1.1811)
			(stroke
				(width 0)
				(type default)
			)
			(fill no)
			(layer "F.CrtYd")
		)
		(fp_rect
			(start -0.635 1.1811)
			(end 0.635 -1.1811)
			(stroke
				(width 0)
				(type default)
			)
			(fill no)
			(layer "F.Fab")
		)
		(pad "1" smd custom
			(at 0 -0.6604 180)
			(size 0.19685 0.19685)
			(layers "F.Cu" "F.Mask" "F.Paste")
			(net "VR_PVDDRA_ISUMN1")
			(options
				(clearance outline)
				(anchor circle)
			)
			(primitives
				(gr_poly
					(pts
						(arc
							(start 0.508 -0.2921)
							(mid 0.478242 -0.363942)
							(end 0.4064 -0.3937)
						)
						(arc
							(start -0.4064 -0.3937)
							(mid -0.478242 -0.363942)
							(end -0.508 -0.2921)
						)
						(arc
							(start -0.508 0.2921)
							(mid -0.478242 0.363942)
							(end -0.4064 0.3937)
						)
						(arc
							(start 0.4064 0.3937)
							(mid 0.478242 0.363942)
							(end 0.508 0.2921)
						)
					)
					(width 0)
					(fill yes)
				)
			)
		)
		(pad "2" smd custom
			(at 0 0.6604 180)
			(size 0.19685 0.19685)
			(layers "F.Cu" "F.Mask" "F.Paste")
			(net "ISENSE_PVDDR_A_ISEN1")
			(options
				(clearance outline)
				(anchor circle)
			)
			(primitives
				(gr_poly
					(pts
						(arc
							(start 0.508 -0.2921)
							(mid 0.478242 -0.363942)
							(end 0.4064 -0.3937)
						)
						(arc
							(start -0.4064 -0.3937)
							(mid -0.478242 -0.363942)
							(end -0.508 -0.2921)
						)
						(arc
							(start -0.508 0.2921)
							(mid -0.478242 0.363942)
							(end -0.4064 0.3937)
						)
						(arc
							(start 0.4064 0.3937)
							(mid 0.478242 0.363942)
							(end 0.508 0.2921)
						)
					)
					(width 0)
					(fill yes)
				)
			)
		)
	)
	(footprint ""
		(layer "F.Cu")
		(at 42.1386 -53.848 180)
		(property "Reference" "PR32"
			(at 0 0 180)
			(layer "F.SilkS")
			(hide yes)
			(effects
				(font
					(size 1.27 1.27)
				)
			)
		)
		(property "Value" "2D2R5F-2-GP"
			(at 0 -4.9022 180)
			(unlocked yes)
			(layer "F.Fab")
			(hide yes)
			(effects
				(font
					(size 1.016 1.016)
					(thickness 0.1524)
				)
			)
		)
		(property "Device Type" "R805H24"
			(at 0 -6.8072 180)
			(unlocked yes)
			(layer "F.Fab")
			(hide yes)
			(effects
				(font
					(size 1.016 1.016)
					(thickness 0.1524)
				)
			)
		)
		(duplicate_pad_numbers_are_jumpers no)
		(fp_line
			(start 0.6096 0)
			(end 0.2794 0)
			(stroke
				(width 0.3048)
				(type default)
			)
			(layer "F.SilkS")
		)
		(fp_line
			(start -0.2794 0)
			(end -0.6096 0)
			(stroke
				(width 0.3048)
				(type default)
			)
			(layer "F.SilkS")
		)
		(fp_poly
			(pts
				(xy -0.9017 1.4351) (xy 0.9017 1.4351) (xy 0.9017 -1.4351) (xy -0.9017 -1.4351)
			)
			(stroke
				(width 0)
				(type default)
			)
			(fill no)
			(layer "F.CrtYd")
		)
		(fp_poly
			(pts
				(xy 0.9017 1.4351) (xy 0.9017 -1.4351) (xy -0.9017 -1.4351) (xy -0.9017 1.4351)
			)
			(stroke
				(width 0)
				(type default)
			)
			(fill no)
			(layer "F.Fab")
		)
		(pad "1" smd rect
			(at 0 -0.8382 180)
			(size 1.5494 0.9398)
			(layers "F.Cu" "F.Mask" "F.Paste")
			(net "VR_PVCCP_VSW_R")
		)
		(pad "2" smd rect
			(at 0 0.8382 180)
			(size 1.5494 0.9398)
			(layers "F.Cu" "F.Mask" "F.Paste")
			(net "GND")
		)
	)
	(footprint ""
		(layer "F.Cu")
		(at 147.828 -18.796)
		(property "Reference" "TP8"
			(at 0 0 0)
			(layer "F.SilkS")
			(hide yes)
			(effects
				(font
					(size 1.27 1.27)
				)
			)
		)
		(property "Value" "TPAD28-1-GP-U"
			(at 0.0508 -1.9304 0)
			(unlocked yes)
			(layer "F.Fab")
			(hide yes)
			(effects
				(font
					(size 1.016 1.016)
					(thickness 0.1524)
				)
			)
		)
		(property "Device Type" "TPAD28-1-U"
			(at 0.0508 -3.4544 0)
			(unlocked yes)
			(layer "F.Fab")
			(hide yes)
			(effects
				(font
					(size 1.016 1.016)
					(thickness 0.1524)
				)
			)
		)
		(duplicate_pad_numbers_are_jumpers no)
		(fp_poly
			(pts
				(arc
					(start 0.3556 0)
					(mid -0.3556 0)
					(end 0.3556 0)
				)
			)
			(stroke
				(width 0)
				(type default)
			)
			(fill no)
			(layer "F.CrtYd")
		)
		(fp_poly
			(pts
				(arc
					(start 0.9525 0)
					(mid -0.9525 0)
					(end 0.9525 0)
				)
			)
			(stroke
				(width 0)
				(type default)
			)
			(fill no)
			(layer "F.Fab")
		)
		(pad "1" smd circle
			(at 0 0)
			(size 0.7112 0.7112)
			(layers "F.Cu" "F.Mask" "F.Paste")
			(net "C_CEO#")
		)
	)
	(footprint ""
		(layer "F.Cu")
		(at 44.831 -27.8384 -90)
		(property "Reference" "R248"
			(at 0 0 270)
			(layer "F.SilkS")
			(hide yes)
			(effects
				(font
					(size 1.27 1.27)
				)
			)
		)
		(property "Value" "1KR2F-3-GP"
			(at 0.064008 -3.993896 270)
			(unlocked yes)
			(layer "F.Fab")
			(hide yes)
			(effects
				(font
					(size 1.016 1.016)
					(thickness 0.1524)
				)
			)
		)
		(property "Device Type" "R402H16"
			(at 0.064008 -5.517896 270)
			(unlocked yes)
			(layer "F.Fab")
			(hide yes)
			(effects
				(font
					(size 1.016 1.016)
					(thickness 0.1524)
				)
			)
		)
		(duplicate_pad_numbers_are_jumpers no)
		(fp_rect
			(start -0.381 0.8382)
			(end 0.381 -0.8382)
			(stroke
				(width 0)
				(type default)
			)
			(fill no)
			(layer "F.CrtYd")
		)
		(fp_rect
			(start -0.381 0.8382)
			(end 0.381 -0.8382)
			(stroke
				(width 0)
				(type default)
			)
			(fill no)
			(layer "F.Fab")
		)
		(pad "1" smd custom
			(at 0 -0.4318 270)
			(size 0.127 0.127)
			(layers "F.Cu" "F.Mask" "F.Paste")
			(net "CPU_RSMRST#")
			(options
				(clearance outline)
				(anchor circle)
			)
			(primitives
				(gr_poly
					(pts
						(arc
							(start -0.2032 -0.2794)
							(mid -0.239121 -0.264521)
							(end -0.254 -0.2286)
						)
						(arc
							(start -0.254 0.2286)
							(mid -0.239121 0.264521)
							(end -0.2032 0.2794)
						)
						(arc
							(start 0.2032 0.2794)
							(mid 0.239121 0.264521)
							(end 0.254 0.2286)
						)
						(arc
							(start 0.254 -0.2286)
							(mid 0.239121 -0.264521)
							(end 0.2032 -0.2794)
						)
					)
					(width 0)
					(fill yes)
				)
			)
		)
		(pad "2" smd custom
			(at 0 0.4318 270)
			(size 0.127 0.127)
			(layers "F.Cu" "F.Mask" "F.Paste")
			(net "XDP_RSMRST_R#")
			(options
				(clearance outline)
				(anchor circle)
			)
			(primitives
				(gr_poly
					(pts
						(arc
							(start -0.2032 -0.2794)
							(mid -0.239121 -0.264521)
							(end -0.254 -0.2286)
						)
						(arc
							(start -0.254 0.2286)
							(mid -0.239121 0.264521)
							(end -0.2032 0.2794)
						)
						(arc
							(start 0.2032 0.2794)
							(mid 0.239121 0.264521)
							(end 0.254 0.2286)
						)
						(arc
							(start 0.254 -0.2286)
							(mid 0.239121 -0.264521)
							(end 0.2032 -0.2794)
						)
					)
					(width 0)
					(fill yes)
				)
			)
		)
	)
)
